(kicad_pcb
	(version 20260206)
	(generator "pcbnew")
	(generator_version "10.0")
	(general
		(thickness 1.6)
		(legacy_teardrops no)
	)
	(paper "A4")
	(title_block
		(title "Bryce Canyon_F.DPB_16315-1-OCP.brd")
		(comment 1 "Bryce Canyon / footprints 1268-1270 of 2223")
	)
	(layers
		(0 "F.Cu" signal "TOP")
		(4 "In1.Cu" signal "L2GND")
		(6 "In2.Cu" signal "L3")
		(8 "In3.Cu" signal "L4GND")
		(10 "In4.Cu" signal "L5")
		(12 "In5.Cu" signal "L6VCC")
		(14 "In6.Cu" signal "L7VCC")
		(16 "In7.Cu" signal "L8")
		(18 "In8.Cu" signal "L9GND")
		(20 "In9.Cu" signal "L10")
		(22 "In10.Cu" signal "L11GND")
		(2 "B.Cu" signal "BOTTOM")
		(9 "F.Adhes" user "F.Adhesive")
		(11 "B.Adhes" user "B.Adhesive")
		(13 "F.Paste" user "Package Geometry/Pastemask Top")
		(15 "B.Paste" user "Package Geometry/Pastemask Bottom")
		(5 "F.SilkS" user "Ref Des/Silkscreen Top")
		(7 "B.SilkS" user "Ref Des/Silkscreen Bottom")
		(1 "F.Mask" user "Board Geometry/Soldermask Top")
		(3 "B.Mask" user "Board Geometry/Soldermask Bottom")
		(17 "Dwgs.User" user "User.Drawings")
		(19 "Cmts.User" user "User.Comments")
		(21 "Eco1.User" user "User.Eco1")
		(23 "Eco2.User" user "User.Eco2")
		(25 "Edge.Cuts" user "Board Geometry/Outline")
		(27 "Margin" user)
		(31 "F.CrtYd" user "Package Geometry/Place Bound Top")
		(29 "B.CrtYd" user "Package Geometry/Place Bound Bottom")
		(35 "F.Fab" user "Ref Des/Assembly Top")
		(33 "B.Fab" user "Ref Des/Assembly Bottom")
	)
	(footprint ""
		(layer "F.Cu")
		(at 232.9434 -248.9708)
		(property "Reference" "R36"
			(at 0 0 0)
			(layer "F.SilkS")
			(hide yes)
			(effects
				(font
					(size 1.27 1.27)
				)
			)
		)
		(property "Value" "4K7R2F-GP"
			(at 0.064008 -3.993896 0)
			(unlocked yes)
			(layer "F.Fab")
			(hide yes)
			(effects
				(font
					(size 1.016 1.016)
					(thickness 0.1524)
				)
			)
		)
		(property "Device Type" "R402H16"
			(at 0.064008 -5.517896 0)
			(unlocked yes)
			(layer "F.Fab")
			(hide yes)
			(effects
				(font
					(size 1.016 1.016)
					(thickness 0.1524)
				)
			)
		)
		(duplicate_pad_numbers_are_jumpers no)
		(fp_line
			(start -0.508 -0.9398)
			(end -0.508 0.9398)
			(stroke
				(width 0.1524)
				(type default)
			)
			(layer "F.SilkS")
		)
		(fp_line
			(start 0.508 -0.9398)
			(end -0.508 -0.9398)
			(stroke
				(width 0.1524)
				(type default)
			)
			(layer "F.SilkS")
		)
		(fp_rect
			(start -0.508 0.9398)
			(end 0.508 -0.9398)
			(stroke
				(width 0)
				(type default)
			)
			(fill no)
			(layer "F.CrtYd")
		)
		(fp_rect
			(start -0.508 0.9398)
			(end 0.508 -0.9398)
			(stroke
				(width 0)
				(type default)
			)
			(fill no)
			(layer "F.Fab")
		)
		(pad "1" smd custom
			(at 0 -0.4445)
			(size 0.1397 0.1397)
			(layers "F.Cu" "F.Mask" "F.Paste")
			(net "IO_EXP4_A0")
			(options
				(clearance outline)
				(anchor circle)
			)
			(primitives
				(gr_poly
					(pts
						(arc
							(start -0.1778 -0.2794)
							(mid -0.249642 -0.249642)
							(end -0.2794 -0.1778)
						)
						(arc
							(start -0.2794 0.1778)
							(mid -0.249642 0.249642)
							(end -0.1778 0.2794)
						)
						(arc
							(start 0.1778 0.2794)
							(mid 0.249642 0.249642)
							(end 0.2794 0.1778)
						)
						(arc
							(start 0.2794 -0.1778)
							(mid 0.249642 -0.249642)
							(end 0.1778 -0.2794)
						)
					)
					(width 0)
					(fill yes)
				)
			)
		)
		(pad "2" smd custom
			(at 0 0.4445)
			(size 0.1397 0.1397)
			(layers "F.Cu" "F.Mask" "F.Paste")
			(net "GND")
			(options
				(clearance outline)
				(anchor circle)
			)
			(primitives
				(gr_poly
					(pts
						(arc
							(start -0.1778 -0.2794)
							(mid -0.249642 -0.249642)
							(end -0.2794 -0.1778)
						)
						(arc
							(start -0.2794 0.1778)
							(mid -0.249642 0.249642)
							(end -0.1778 0.2794)
						)
						(arc
							(start 0.1778 0.2794)
							(mid 0.249642 0.249642)
							(end 0.2794 0.1778)
						)
						(arc
							(start 0.2794 -0.1778)
							(mid 0.249642 -0.249642)
							(end 0.1778 -0.2794)
						)
					)
					(width 0)
					(fill yes)
				)
			)
		)
	)
	(footprint ""
		(layer "F.Cu")
		(at 332.74 -279.596342 90)
		(property "Reference" "C126"
			(at 0 0 90)
			(layer "F.SilkS")
			(hide yes)
			(effects
				(font
					(size 1.27 1.27)
				)
			)
		)
		(property "Value" "SCD033U25V2KX-GP"
			(at 1.1811 -2.7051 90)
			(unlocked yes)
			(layer "F.Fab")
			(hide yes)
			(effects
				(font
					(size 1.016 1.016)
					(thickness 0.1524)
				)
			)
		)
		(property "Device Type" "C402H22"
			(at 1.1811 -4.2291 90)
			(unlocked yes)
			(layer "F.Fab")
			(hide yes)
			(effects
				(font
					(size 1.016 1.016)
					(thickness 0.1524)
				)
			)
		)
		(duplicate_pad_numbers_are_jumpers no)
		(fp_rect
			(start -0.4318 0.9525)
			(end 0.4318 -0.9525)
			(stroke
				(width 0)
				(type default)
			)
			(fill no)
			(layer "F.CrtYd")
		)
		(fp_rect
			(start -0.4318 0.9525)
			(end 0.4318 -0.9525)
			(stroke
				(width 0)
				(type default)
			)
			(fill no)
			(layer "F.Fab")
		)
		(pad "1" smd custom
			(at 0 -0.4445 90)
			(size 0.1524 0.1524)
			(layers "F.Cu" "F.Mask" "F.Paste")
			(net "SW_HDD_P6")
			(options
				(clearance outline)
				(anchor circle)
			)
			(primitives
				(gr_poly
					(pts
						(arc
							(start 0.3048 -0.2032)
							(mid 0.275042 -0.275042)
							(end 0.2032 -0.3048)
						)
						(arc
							(start -0.2032 -0.3048)
							(mid -0.275042 -0.275042)
							(end -0.3048 -0.2032)
						)
						(arc
							(start -0.3048 0.2032)
							(mid -0.275042 0.275042)
							(end -0.2032 0.3048)
						)
						(arc
							(start 0.2032 0.3048)
							(mid 0.275042 0.275042)
							(end 0.3048 0.2032)
						)
					)
					(width 0)
					(fill yes)
				)
			)
		)
		(pad "2" smd custom
			(at 0 0.4445 90)
			(size 0.1524 0.1524)
			(layers "F.Cu" "F.Mask" "F.Paste")
			(net "GND")
			(options
				(clearance outline)
				(anchor circle)
			)
			(primitives
				(gr_poly
					(pts
						(arc
							(start 0.3048 -0.2032)
							(mid 0.275042 -0.275042)
							(end 0.2032 -0.3048)
						)
						(arc
							(start -0.2032 -0.3048)
							(mid -0.275042 -0.275042)
							(end -0.3048 -0.2032)
						)
						(arc
							(start -0.3048 0.2032)
							(mid -0.275042 0.275042)
							(end -0.2032 0.3048)
						)
						(arc
							(start 0.2032 0.3048)
							(mid 0.275042 0.275042)
							(end 0.3048 0.2032)
						)
					)
					(width 0)
					(fill yes)
				)
			)
		)
	)
	(footprint ""
		(layer "F.Cu")
		(at 28.200096 -287.910016 -90)
		(property "Reference" "HDDSAS0"
			(at 0 0 270)
			(layer "F.SilkS")
			(hide yes)
			(effects
				(font
					(size 1.27 1.27)
				)
			)
		)
		(property "Value" "SKT-SAS15P-14P-45-GP"
			(at -20.7645 -8.9789 270)
			(unlocked yes)
			(layer "F.Fab")
			(hide yes)
			(effects
				(font
					(size 1.016 1.016)
					(thickness 0.1524)
				)
			)
		)
		(property "Device Type" "10120818-001C-TRLF"
			(at -20.7645 -10.5029 270)
			(unlocked yes)
			(layer "F.Fab")
			(hide yes)
			(effects
				(font
					(size 1.016 1.016)
					(thickness 0.1524)
				)
			)
		)
		(duplicate_pad_numbers_are_jumpers no)
		(fp_line
			(start 1.651 4.2926)
			(end 1.651 3.0099)
			(stroke
				(width 0.1524)
				(type default)
			)
			(layer "F.SilkS")
		)
		(fp_line
			(start 8.509 4.2926)
			(end 1.651 4.2926)
			(stroke
				(width 0.1524)
				(type default)
			)
			(layer "F.SilkS")
		)
		(fp_line
			(start -23.4188 3.0099)
			(end -23.4188 -3.2512)
			(stroke
				(width 0.1524)
				(type default)
			)
			(layer "F.SilkS")
		)
		(fp_line
			(start 1.651 3.0099)
			(end -23.4188 3.0099)
			(stroke
				(width 0.1524)
				(type default)
			)
			(layer "F.SilkS")
		)
		(fp_line
			(start 8.509 3.0099)
			(end 8.509 4.2926)
			(stroke
				(width 0.1524)
				(type default)
			)
			(layer "F.SilkS")
		)
		(fp_line
			(start 23.4188 3.0099)
			(end 8.509 3.0099)
			(stroke
				(width 0.1524)
				(type default)
			)
			(layer "F.SilkS")
		)
		(fp_line
			(start -23.4188 -3.2512)
			(end 23.4188 -3.2512)
			(stroke
				(width 0.1524)
				(type default)
			)
			(layer "F.SilkS")
		)
		(fp_line
			(start 23.4188 -3.2512)
			(end 23.4188 3.0099)
			(stroke
				(width 0.1524)
				(type default)
			)
			(layer "F.SilkS")
		)
		(fp_line
			(start 15.5067 -3.3401)
			(end 16.2687 -3.3401)
			(stroke
				(width 0.3302)
				(type default)
			)
			(layer "F.SilkS")
		)
		(fp_poly
			(pts
				(xy 15.868904 -3.230372) (xy 16.503904 -3.865372) (xy 15.233904 -3.865372)
			)
			(stroke
				(width 0)
				(type default)
			)
			(fill yes)
			(layer "F.SilkS")
		)
		(fp_poly
			(pts
				(xy -22.8727 -2.7559) (xy 22.8727 -2.7559) (xy 22.8727 2.7559) (xy 8.255 2.7559) (xy 8.255 3.5179)
				(xy 1.905 3.5179) (xy 1.905 2.7559) (xy -22.8727 2.7559)
			)
			(stroke
				(width 0)
				(type default)
			)
			(fill no)
			(layer "F.CrtYd")
		)
		(fp_poly
			(pts
				(xy 1.397 4.5466) (xy 1.397 3.2639) (xy -23.6728 3.2639) (xy -23.6728 -3.5052) (xy 23.6728 -3.5052)
				(xy 23.6728 -0.00635) (xy 22.8727 -0.00635) (xy 22.8727 -2.7559) (xy -22.8727 -2.7559) (xy -22.8727 2.7559)
				(xy 1.905 2.7559) (xy 1.905 3.5179) (xy 8.255 3.5179) (xy 8.255 2.7559) (xy 22.8727 2.7559) (xy 22.8727 0.00635)
				(xy 23.6728 0.00635) (xy 23.6728 3.2639) (xy 8.763 3.2639) (xy 8.763 4.5466)
			)
			(stroke
				(width 0)
				(type default)
			)
			(fill no)
			(layer "F.CrtYd")
		)
		(fp_poly
			(pts
				(xy 1.397 4.5466) (xy 1.397 3.2639) (xy -23.6728 3.2639) (xy -23.6728 -3.5052) (xy 23.6728 -3.5052)
				(xy 23.6728 3.2639) (xy 8.763 3.2639) (xy 8.763 4.5466)
			)
			(stroke
				(width 0)
				(type default)
			)
			(fill no)
			(layer "F.Fab")
		)
		(pad "" np_thru_hole circle
			(at -18.874994 0 270)
			(size 0.254 0.254)
			(drill 1.3462)
			(layers "*.Cu" "*.Mask")
			(clearance 0.9017)
			(thermal_gap 0.9017)
		)
		(pad "" np_thru_hole circle
			(at 18.874994 0 270)
			(size 0.254 0.254)
			(drill 0.9398)
			(layers "*.Cu" "*.Mask")
			(clearance 0.6985)
			(thermal_gap 0.6985)
		)
		(pad "G1" smd rect
			(at 21.874988 0 270)
			(size 2.5908 2.5908)
			(layers "F.Cu" "F.Mask" "F.Paste")
			(net "GND")
		)
		(pad "G2" smd rect
			(at -21.874988 0 270)
			(size 2.5908 2.5908)
			(layers "F.Cu" "F.Mask" "F.Paste")
			(net "GND")
		)
		(pad "P1" smd rect
			(at 1.905 -1.82499 270)
			(size 0.6096 2.3622)
			(layers "F.Cu" "F.Mask" "F.Paste")
			(net "Net_2176")
		)
		(pad "P2" smd rect
			(at 0.635 -1.82499 270)
			(size 0.6096 2.3622)
			(layers "F.Cu" "F.Mask" "F.Paste")
			(net "Net_2177")
		)
		(pad "P3" smd rect
			(at -0.635 -1.82499 270)
			(size 0.6096 2.3622)
			(layers "F.Cu" "F.Mask" "F.Paste")
			(net "Net_2178")
		)
		(pad "P4" smd rect
			(at -1.905 -1.82499 270)
			(size 0.6096 2.3622)
			(layers "F.Cu" "F.Mask" "F.Paste")
			(net "GND")
		)
		(pad "P5" smd rect
			(at -3.175 -1.82499 270)
			(size 0.6096 2.3622)
			(layers "F.Cu" "F.Mask" "F.Paste")
			(net "HDD_PRSNT_0")
		)
		(pad "P6" smd rect
			(at -4.445 -1.82499 270)
			(size 0.6096 2.3622)
			(layers "F.Cu" "F.Mask" "F.Paste")
			(net "GND")
		)
		(pad "P7" smd rect
			(at -5.715 -1.82499 270)
			(size 0.6096 2.3622)
			(layers "F.Cu" "F.Mask" "F.Paste")
			(net "5V_PRE_0")
		)
		(pad "P8" smd rect
			(at -6.985 -1.82499 270)
			(size 0.6096 2.3622)
			(layers "F.Cu" "F.Mask" "F.Paste")
			(net "P5V_HDD0")
		)
		(pad "P9" smd rect
			(at -8.255 -1.82499 270)
			(size 0.6096 2.3622)
			(layers "F.Cu" "F.Mask" "F.Paste")
			(net "P5V_HDD0")
		)
		(pad "P10" smd rect
			(at -9.525 -1.82499 270)
			(size 0.6096 2.3622)
			(layers "F.Cu" "F.Mask" "F.Paste")
			(net "GND")
		)
		(pad "P11" smd rect
			(at -10.795 -1.82499 270)
			(size 0.6096 2.3622)
			(layers "F.Cu" "F.Mask" "F.Paste")
			(net "ACT_HDD_0")
		)
		(pad "P12" smd rect
			(at -12.065 -1.82499 270)
			(size 0.6096 2.3622)
			(layers "F.Cu" "F.Mask" "F.Paste")
			(net "GND")
		)
		(pad "P13" smd rect
			(at -13.335 -1.82499 270)
			(size 0.6096 2.3622)
			(layers "F.Cu" "F.Mask" "F.Paste")
			(net "12V_PRE_0")
		)
		(pad "P14" smd rect
			(at -14.605 -1.82499 270)
			(size 0.6096 2.3622)
			(layers "F.Cu" "F.Mask" "F.Paste")
			(net "P12V_HDD0")
		)
		(pad "P15" smd rect
			(at -15.875 -1.82499 270)
			(size 0.6096 2.3622)
			(layers "F.Cu" "F.Mask" "F.Paste")
			(net "P12V_HDD0")
		)
		(pad "S1" smd rect
			(at 15.875 -1.82499 270)
			(size 0.6096 2.3622)
			(layers "F.Cu" "F.Mask" "F.Paste")
			(net "GND")
		)
		(pad "S2" smd rect
			(at 14.605 -1.82499 270)
			(size 0.6096 2.3622)
			(layers "F.Cu" "F.Mask" "F.Paste")
			(net "SAS_HDD_RX_P0")
		)
		(pad "S3" smd rect
			(at 13.335 -1.82499 270)
			(size 0.6096 2.3622)
			(layers "F.Cu" "F.Mask" "F.Paste")
			(net "SAS_HDD_RX_N0")
		)
		(pad "S4" smd rect
			(at 12.065 -1.82499 270)
			(size 0.6096 2.3622)
			(layers "F.Cu" "F.Mask" "F.Paste")
			(net "GND")
		)
		(pad "S5" smd rect
			(at 10.795 -1.82499 270)
			(size 0.6096 2.3622)
			(layers "F.Cu" "F.Mask" "F.Paste")
			(net "PHY_DRV_A_TO_SCC_A_0_DN")
		)
		(pad "S6" smd rect
			(at 9.525 -1.82499 270)
			(size 0.6096 2.3622)
			(layers "F.Cu" "F.Mask" "F.Paste")
			(net "PHY_DRV_A_TO_SCC_A_0_DP")
		)
		(pad "S7" smd rect
			(at 8.255 -1.82499 270)
			(size 0.6096 2.3622)
			(layers "F.Cu" "F.Mask" "F.Paste")
			(net "GND")
		)
		(pad "S8" smd rect
			(at 7.480046 2.845054 270)
			(size 0.508 2.3622)
			(layers "F.Cu" "F.Mask" "F.Paste")
			(net "GND")
		)
		(pad "S9" smd rect
			(at 6.679946 2.845054 270)
			(size 0.508 2.3622)
			(layers "F.Cu" "F.Mask" "F.Paste")
			(net "Net_445")
		)
		(pad "S10" smd rect
			(at 5.8801 2.845054 270)
			(size 0.508 2.3622)
			(layers "F.Cu" "F.Mask" "F.Paste")
			(net "Net_337")
		)
		(pad "S11" smd rect
			(at 5.08 2.845054 270)
			(size 0.508 2.3622)
			(layers "F.Cu" "F.Mask" "F.Paste")
			(net "GND")
		)
		(pad "S12" smd rect
			(at 4.2799 2.845054 270)
			(size 0.508 2.3622)
			(layers "F.Cu" "F.Mask" "F.Paste")
			(net "Net_373")
		)
		(pad "S13" smd rect
			(at 3.480054 2.845054 270)
			(size 0.508 2.3622)
			(layers "F.Cu" "F.Mask" "F.Paste")
			(net "Net_409")
		)
		(pad "S14" smd rect
			(at 2.679954 2.845054 270)
			(size 0.508 2.3622)
			(layers "F.Cu" "F.Mask" "F.Paste")
			(net "GND")
		)
		(zone
			(layer "F.Cu")
			(hatch none 0.5)
			(connect_pads
				(clearance 0)
			)
			(min_thickness 0.25)
			(keepout
				(tracks not_allowed)
				(vias allowed)
				(pads allowed)
				(copperpour not_allowed)
				(footprints allowed)
			)
			(placement
				(enabled no)
				(sheetname "")
			)
			(fill
				(thermal_gap 0.5)
				(thermal_bridge_width 0.5)
				(island_removal_mode 0)
			)
			(polygon
				(pts
					(xy 31.857696 -304.648616) (xy 24.783796 -304.648616) (xy 24.783796 -311.582816) (xy 25.888696 -311.582816)
					(xy 25.888696 -307.468016) (xy 30.511496 -307.468016) (xy 30.511496 -311.582816) (xy 31.857696 -311.582816)
				)
			)
		)
		(zone
			(layer "F.Cu")
			(hatch none 0.5)
			(connect_pads
				(clearance 0)
			)
			(min_thickness 0.25)
			(keepout
				(tracks allowed)
				(vias not_allowed)
				(pads allowed)
				(copperpour not_allowed)
				(footprints allowed)
			)
			(placement
				(enabled no)
				(sheetname "")
			)
			(fill
				(thermal_gap 0.5)
				(thermal_bridge_width 0.5)
				(island_removal_mode 0)
			)
			(polygon
				(pts
					(xy 31.857696 -304.648616) (xy 24.783796 -304.648616) (xy 24.783796 -311.582816) (xy 25.888696 -311.582816)
					(xy 25.888696 -307.468016) (xy 30.511496 -307.468016) (xy 30.511496 -311.582816) (xy 31.857696 -311.582816)
				)
			)
		)
		(zone
			(layer "F.Cu")
			(hatch none 0.5)
			(connect_pads
				(clearance 0)
			)
			(min_thickness 0.25)
			(keepout
				(tracks not_allowed)
				(vias allowed)
				(pads allowed)
				(copperpour not_allowed)
				(footprints allowed)
			)
			(placement
				(enabled no)
				(sheetname "")
			)
			(fill
				(thermal_gap 0.5)
				(thermal_bridge_width 0.5)
				(island_removal_mode 0)
			)
			(polygon
				(pts
					(xy 31.857696 -271.171416) (xy 24.783796 -271.171416) (xy 24.783796 -264.237216) (xy 25.888696 -264.237216)
					(xy 25.888696 -268.352016) (xy 30.511496 -268.352016) (xy 30.511496 -264.237216) (xy 31.857696 -264.237216)
				)
			)
		)
		(zone
			(layer "F.Cu")
			(hatch none 0.5)
			(connect_pads
				(clearance 0)
			)
			(min_thickness 0.25)
			(keepout
				(tracks allowed)
				(vias not_allowed)
				(pads allowed)
				(copperpour not_allowed)
				(footprints allowed)
			)
			(placement
				(enabled no)
				(sheetname "")
			)
			(fill
				(thermal_gap 0.5)
				(thermal_bridge_width 0.5)
				(island_removal_mode 0)
			)
			(polygon
				(pts
					(xy 31.857696 -271.171416) (xy 24.783796 -271.171416) (xy 24.783796 -264.237216) (xy 25.888696 -264.237216)
					(xy 25.888696 -268.352016) (xy 30.511496 -268.352016) (xy 30.511496 -264.237216) (xy 31.857696 -264.237216)
				)
			)
		)
		(zone
			(layers "F.Cu" "B.Cu" "In1.Cu" "In2.Cu" "In3.Cu" "In4.Cu" "In5.Cu" "In6.Cu"
				"In7.Cu" "In8.Cu" "In9.Cu" "In10.Cu"
			)
			(hatch none 0.5)
			(connect_pads
				(clearance 0)
			)
			(min_thickness 0.25)
			(keepout
				(tracks not_allowed)
				(vias allowed)
				(pads allowed)
				(copperpour not_allowed)
				(footprints allowed)
			)
			(placement
				(enabled no)
				(sheetname "")
			)
			(fill
				(thermal_gap 0.5)
				(thermal_bridge_width 0.5)
				(island_removal_mode 0)
			)
			(polygon
				(pts
					(arc
						(start 28.974796 -269.035022)
						(mid 27.425396 -269.035022)
						(end 28.974796 -269.035022)
					)
				)
			)
		)
		(zone
			(layers "F.Cu" "B.Cu" "In1.Cu" "In2.Cu" "In3.Cu" "In4.Cu" "In5.Cu" "In6.Cu"
				"In7.Cu" "In8.Cu" "In9.Cu" "In10.Cu"
			)
			(hatch none 0.5)
			(connect_pads
				(clearance 0)
			)
			(min_thickness 0.25)
			(keepout
				(tracks not_allowed)
				(vias allowed)
				(pads allowed)
				(copperpour not_allowed)
				(footprints allowed)
			)
			(placement
				(enabled no)
				(sheetname "")
			)
			(fill
				(thermal_gap 0.5)
				(thermal_bridge_width 0.5)
				(island_removal_mode 0)
			)
			(polygon
				(pts
					(arc
						(start 29.177996 -306.78501)
						(mid 27.222196 -306.78501)
						(end 29.177996 -306.78501)
					)
				)
			)
		)
	)
)
